# BASEBOARD_FAB2 (Tioga Pass) — schematic netlist excerpt (pin names and nets, part order shuffled) for the footprints in the layout excerpt that follows; sources: Cadence DE-HDL packaged netlist, KiCad conversion of Wiwynn_Tioga_Pass_MB.brd

R2N22  RES  49.9 1% CHIP  pkg 0402  page 178 : A = SGPIO_PCH_SSATA_CLOCK ; B = SGPIO_PCH_SSATA_CLOCK_R
C5G84  CAP_A  22.0UF 4V 20% X6S  pkg 0603V  page 243 : A = PVDDQ_GHJ ; B = GND
C5U14  CAP  100UF 4V 20% X5R  pkg 0805  page 217 : A = PVDDQ_ABC ; B = GND

(kicad_pcb
	(version 20260206)
	(generator "pcbnew")
	(generator_version "10.0")
	(general
		(thickness 1.6)
		(legacy_teardrops no)
	)
	(paper "A4")
	(title_block
		(title "Wiwynn_Tioga_Pass_MB.brd")
		(comment 1 "Tioga Pass / footprints 3162-3164 of 4770")
	)
	(layers
		(0 "F.Cu" signal "TOP")
		(4 "In1.Cu" signal "L2GND")
		(6 "In2.Cu" signal "L3")
		(8 "In3.Cu" signal "L4GND")
		(10 "In4.Cu" signal "L5")
		(12 "In5.Cu" signal "L6GND")
		(14 "In6.Cu" signal "L7VCC")
		(16 "In7.Cu" signal "L8VCC")
		(18 "In8.Cu" signal "L9GND")
		(20 "In9.Cu" signal "L10")
		(22 "In10.Cu" signal "L11GND")
		(24 "In11.Cu" signal "L12")
		(26 "In12.Cu" signal "L13GND")
		(2 "B.Cu" signal "BOTTOM")
		(9 "F.Adhes" user "F.Adhesive")
		(11 "B.Adhes" user "B.Adhesive")
		(13 "F.Paste" user "Package Geometry/Pastemask Top")
		(15 "B.Paste" user "Package Geometry/Pastemask Bottom")
		(5 "F.SilkS" user "Ref Des/Silkscreen Top")
		(7 "B.SilkS" user "Ref Des/Silkscreen Bottom")
		(1 "F.Mask" user "Board Geometry/Soldermask Top")
		(3 "B.Mask" user "Board Geometry/Soldermask Bottom")
		(17 "Dwgs.User" user "User.Drawings")
		(19 "Cmts.User" user "User.Comments")
		(21 "Eco1.User" user "User.Eco1")
		(23 "Eco2.User" user "User.Eco2")
		(25 "Edge.Cuts" user "Board Geometry/Outline")
		(27 "Margin" user)
		(31 "F.CrtYd" user "Package Geometry/Place Bound Top")
		(29 "B.CrtYd" user "Package Geometry/Place Bound Bottom")
		(35 "F.Fab" user "Ref Des/Assembly Top")
		(33 "B.Fab" user "Ref Des/Assembly Bottom")
	)
	(footprint ""
		(layer "B.Cu")
		(at 390.144 -87.4395)
		(property "Reference" "R2N22"
			(at 0.8382 -0.67818 0)
			(unlocked yes)
			(layer "B.SilkS")
			(effects
				(font
					(size 0.4064 0.254)
					(thickness 0.1524)
				)
				(justify left mirror)
			)
		)
		(property "Value" ""
			(at 0 0 0)
			(layer "B.Fab")
			(effects
				(font
					(size 1.27 1.27)
				)
				(justify mirror)
			)
		)
		(duplicate_pad_numbers_are_jumpers no)
		(fp_poly
			(pts
				(xy 0.2794 -0.1016) (xy -0.2794 -0.1016) (xy -0.2794 0.9906) (xy 0.2794 0.9906)
			)
			(stroke
				(width 0)
				(type default)
			)
			(fill no)
			(layer "B.CrtYd")
		)
		(fp_line
			(start -0.2794 -0.1016)
			(end 0.2794 -0.1016)
			(stroke
				(width 0.1)
				(type default)
			)
			(layer "B.Fab")
		)
		(fp_line
			(start -0.2794 0.9906)
			(end -0.2794 -0.1016)
			(stroke
				(width 0.1)
				(type default)
			)
			(layer "B.Fab")
		)
		(fp_line
			(start 0.2794 -0.1016)
			(end 0.2794 0.9906)
			(stroke
				(width 0.1)
				(type default)
			)
			(layer "B.Fab")
		)
		(fp_line
			(start 0.2794 0.9906)
			(end -0.2794 0.9906)
			(stroke
				(width 0.1)
				(type default)
			)
			(layer "B.Fab")
		)
		(pad "1" smd rect
			(at 0 0 180)
			(size 0.508 0.508)
			(layers "B.Cu" "B.Mask" "B.Paste")
			(net "SGPIO_PCH_SSATA_CLOCK")
		)
		(pad "2" smd rect
			(at 0 0.889 180)
			(size 0.508 0.508)
			(layers "B.Cu" "B.Mask" "B.Paste")
			(net "SGPIO_PCH_SSATA_CLOCK_R")
		)
		(zone
			(layer "B.Cu")
			(hatch none 0.5)
			(connect_pads
				(clearance 0)
			)
			(min_thickness 0.25)
			(keepout
				(tracks allowed)
				(vias not_allowed)
				(pads allowed)
				(copperpour not_allowed)
				(footprints allowed)
			)
			(placement
				(enabled no)
				(sheetname "")
			)
			(fill
				(thermal_gap 0.5)
				(thermal_bridge_width 0.5)
				(island_removal_mode 0)
			)
			(polygon
				(pts
					(xy 390.398 -87.1855) (xy 389.89 -87.1855) (xy 389.89 -86.8045) (xy 390.398 -86.8045)
				)
			)
		)
		(zone
			(layer "B.Cu")
			(hatch none 0.5)
			(connect_pads
				(clearance 0)
			)
			(min_thickness 0.25)
			(keepout
				(tracks not_allowed)
				(vias allowed)
				(pads allowed)
				(copperpour not_allowed)
				(footprints allowed)
			)
			(placement
				(enabled no)
				(sheetname "")
			)
			(fill
				(thermal_gap 0.5)
				(thermal_bridge_width 0.5)
				(island_removal_mode 0)
			)
			(polygon
				(pts
					(xy 390.398 -86.8045) (xy 389.89 -86.8045) (xy 389.89 -87.1855) (xy 390.398 -87.1855)
				)
			)
		)
	)
	(footprint ""
		(layer "B.Cu")
		(at 93.101668 -3.321812 -90)
		(property "Reference" "C5G84"
			(at -1.14681 0.76708 0)
			(unlocked yes)
			(layer "B.SilkS")
			(effects
				(font
					(size 0.7874 0.5842)
					(thickness 0.1524)
				)
				(justify mirror)
			)
		)
		(property "Value" ""
			(at 0 0 90)
			(layer "B.Fab")
			(effects
				(font
					(size 1.27 1.27)
				)
				(justify mirror)
			)
		)
		(duplicate_pad_numbers_are_jumpers no)
		(fp_rect
			(start 0.4953 1.6002)
			(end -0.4953 -0.2032)
			(stroke
				(width 0)
				(type default)
			)
			(fill no)
			(layer "B.CrtYd")
		)
		(fp_line
			(start -0.4953 1.6002)
			(end 0.4953 1.6002)
			(stroke
				(width 0.1)
				(type default)
			)
			(layer "B.Fab")
		)
		(fp_line
			(start 0.4953 1.6002)
			(end 0.4953 -0.2032)
			(stroke
				(width 0.1)
				(type default)
			)
			(layer "B.Fab")
		)
		(fp_line
			(start -0.4953 -0.2032)
			(end -0.4953 1.6002)
			(stroke
				(width 0.1)
				(type default)
			)
			(layer "B.Fab")
		)
		(fp_line
			(start 0.4953 -0.2032)
			(end -0.4953 -0.2032)
			(stroke
				(width 0.1)
				(type default)
			)
			(layer "B.Fab")
		)
		(pad "1" smd rect
			(at 0 0 90)
			(size 0.762 0.889)
			(layers "B.Cu" "B.Mask" "B.Paste")
			(net "PVDDQ_GHJ")
		)
		(pad "2" smd rect
			(at 0 1.397 90)
			(size 0.762 0.889)
			(layers "B.Cu" "B.Mask" "B.Paste")
			(net "GND")
		)
		(zone
			(layer "B.Cu")
			(hatch none 0.5)
			(connect_pads
				(clearance 0)
			)
			(min_thickness 0.25)
			(keepout
				(tracks not_allowed)
				(vias allowed)
				(pads allowed)
				(copperpour not_allowed)
				(footprints allowed)
			)
			(placement
				(enabled no)
				(sheetname "")
			)
			(fill
				(thermal_gap 0.5)
				(thermal_bridge_width 0.5)
				(island_removal_mode 0)
			)
			(polygon
				(pts
					(xy 92.149168 -2.940812) (xy 92.657168 -2.940812) (xy 92.657168 -3.702812) (xy 92.149168 -3.702812)
				)
			)
		)
	)
	(footprint ""
		(layer "B.Cu")
		(at 270.637 3.81 90)
		(property "Reference" "C5U14"
			(at 0 0 90)
			(layer "B.SilkS")
			(hide yes)
			(effects
				(font
					(size 1.27 1.27)
				)
				(justify mirror)
			)
		)
		(property "Value" ""
			(at 0 0 90)
			(layer "B.Fab")
			(effects
				(font
					(size 1.27 1.27)
				)
				(justify mirror)
			)
		)
		(duplicate_pad_numbers_are_jumpers no)
		(fp_rect
			(start -0.7239 -0.2159)
			(end 0.7239 1.9939)
			(stroke
				(width 0)
				(type default)
			)
			(fill no)
			(layer "B.CrtYd")
		)
		(fp_line
			(start 0.7239 -0.2159)
			(end 0.7239 1.9939)
			(stroke
				(width 0.1)
				(type default)
			)
			(layer "B.Fab")
		)
		(fp_line
			(start -0.7239 -0.2159)
			(end 0.7239 -0.2159)
			(stroke
				(width 0.1)
				(type default)
			)
			(layer "B.Fab")
		)
		(fp_line
			(start 0.7239 1.9939)
			(end -0.7239 1.9939)
			(stroke
				(width 0.1)
				(type default)
			)
			(layer "B.Fab")
		)
		(fp_line
			(start -0.7239 1.9939)
			(end -0.7239 -0.2159)
			(stroke
				(width 0.1)
				(type default)
			)
			(layer "B.Fab")
		)
		(pad "1" smd rect
			(at 0 0 270)
			(size 1.27 1.016)
			(layers "B.Cu" "B.Mask" "B.Paste")
			(net "PVDDQ_ABC")
		)
		(pad "2" smd rect
			(at 0 1.778 270)
			(size 1.27 1.016)
			(layers "B.Cu" "B.Mask" "B.Paste")
			(net "GND")
		)
		(zone
			(layer "B.Cu")
			(hatch none 0.5)
			(connect_pads
				(clearance 0)
			)
			(min_thickness 0.25)
			(keepout
				(tracks not_allowed)
				(vias allowed)
				(pads allowed)
				(copperpour not_allowed)
				(footprints allowed)
			)
			(placement
				(enabled no)
				(sheetname "")
			)
			(fill
				(thermal_gap 0.5)
				(thermal_bridge_width 0.5)
				(island_removal_mode 0)
			)
			(polygon
				(pts
					(xy 271.145 4.445) (xy 271.907 4.445) (xy 271.907 3.175) (xy 271.145 3.175)
				)
			)
		)
	)
)
